(kicad_pcb
	(version 20221018)
	(generator pcbnew)
	(general
    (thickness 1.518)
  )
	(paper "A4")
	(title_block
    (title "Kria K26 Devboard")
    (date "2024-03-26")
    (rev "1.2.5")
    (comment 1 "www.antmicro.com")
    (comment 2 "Antmicro Ltd.")
		(comment 9 "footprints 97-104 of 660")
	)
	(layers
    (0 "F.Cu" mixed)
    (1 "In1.Cu" power)
    (2 "In2.Cu" mixed)
    (3 "In3.Cu" power)
    (4 "In4.Cu" mixed)
    (5 "In5.Cu" power)
    (6 "In6.Cu" mixed)
    (31 "B.Cu" power)
    (32 "B.Adhes" user "B.Adhesive")
    (33 "F.Adhes" user "F.Adhesive")
    (34 "B.Paste" user)
    (35 "F.Paste" user)
    (36 "B.SilkS" user "B.Silkscreen")
    (37 "F.SilkS" user "F.Silkscreen")
    (38 "B.Mask" user)
    (39 "F.Mask" user)
    (40 "Dwgs.User" user "User.Drawings")
    (41 "Cmts.User" user "User.Comments")
    (42 "Eco1.User" user "User.Eco1")
    (43 "Eco2.User" user "User.Eco2")
    (44 "Edge.Cuts" user)
    (45 "Margin" user)
    (46 "B.CrtYd" user "B.Courtyard")
    (47 "F.CrtYd" user "F.Courtyard")
    (48 "B.Fab" user)
    (49 "F.Fab" user)
  )
	(footprint "kria-k26-devboard-footprints:R_0402_1005Metric" (layer "F.Cu")
    (at 127.83 91.56 180)
    (descr "Resistor SMD 0402")
    (tags "resistor SMD 0402")
    (property "Author" "Antmicro")
    (property "License" "Apache-2.0")
    (property "MPN" "CR0402-FX-1202GLF")
    (property "Manufacturer" "Bourns")
    (property "Sheetfile" "usb.kicad_sch")
    (property "Sheetname" "USB")
    (property "Tolerance" "1%")
    (property "Val" "12k")
    (property "ki_description" "12k resistor in 0402 package with 1% tolerance")
    (attr smd)
    (fp_text reference "R52" (at -0.79 -0.57 180) (layer "F.SilkS")
        (effects (font (size 0.7 0.7) (thickness 0.15)) (justify left bottom))
    )
    (fp_text value "R_12k_0402" (at 0 1.4 180) (layer "F.Fab") hide
        (effects (font (size 0.7 0.7) (thickness 0.15)) (justify left bottom))
    )
    (fp_text user "${REFERENCE}" (at -0.95 3.168 180) (layer "F.Fab") hide
        (effects (font (size 0.7 0.7) (thickness 0.15)) (justify left bottom))
    )
    (fp_text user "License: Apache-2.0" (at -0.95 5.169 180) (layer "F.Fab") hide
        (effects (font (size 0.7 0.7) (thickness 0.15)) (justify left bottom))
    )
    (fp_text user "Author: Antmicro" (at -0.95 4.169 180) (layer "F.Fab") hide
        (effects (font (size 0.7 0.7) (thickness 0.15)) (justify left bottom))
    )
    (fp_rect (start -0.93 -0.47) (end 0.93 0.47)
      (stroke (width 0.05) (type solid)) (fill none) (layer "F.CrtYd"))
    (fp_rect (start -0.5 -0.25) (end 0.5 0.25)
      (stroke (width 0.15) (type solid)) (fill none) (layer "F.Fab"))
    (pad "1" smd roundrect (at -0.485 0 180) (size 0.59 0.64) (layers "F.Cu" "F.Paste" "F.Mask") (roundrect_rratio 0.25)
      (net 1 "GND") (pintype "passive"))
    (pad "2" smd roundrect (at 0.485 0 180) (size 0.59 0.64) (layers "F.Cu" "F.Paste" "F.Mask") (roundrect_rratio 0.25)
      (net 655 "Net-(U17-RBIAS)") (pintype "passive"))
  )
	(footprint "kria-k26-devboard-footprints:SOT-416" (layer "F.Cu")
    (at 107.7 136.2 90)
    (descr "SOT-416")
    (tags "SOT-416")
    (property "Author" "Antmicro")
    (property "License" "Apache-2.0")
    (property "MPN" "DTC014TEBTL")
    (property "Manufacturer" "ROHM Semiconductor")
    (property "Sheetfile" "reset.kicad_sch")
    (property "Sheetname" "Reset logic")
    (property "ki_description" "Digital NPN Transistor, 10k/NONE, EMT-3")
    (attr smd)
    (fp_text reference "Q8" (at 1.08 -0.85 180) (layer "F.SilkS")
        (effects (font (size 0.7 0.7) (thickness 0.15)) (justify left bottom))
    )
    (fp_text value "DTC014T_SOT-416" (at 0 2 90) (layer "F.Fab") hide
        (effects (font (size 0.7 0.7) (thickness 0.15)) (justify left bottom))
    )
    (fp_text user "Author: Antmicro" (at -1 4.602 90) (layer "F.Fab") hide
        (effects (font (size 0.7 0.7) (thickness 0.15)) (justify left bottom))
    )
    (fp_text user "${REFERENCE}" (at -1 3.4 90) (layer "F.Fab") hide
        (effects (font (size 0.7 0.7) (thickness 0.15)) (justify left bottom))
    )
    (fp_text user "License: Apache-2.0" (at -1 5.802 90) (layer "F.Fab") hide
        (effects (font (size 0.7 0.7) (thickness 0.15)) (justify left bottom))
    )
    (fp_line (start -0.5 -0.15) (end -0.5 0.15)
      (stroke (width 0.15) (type solid)) (layer "F.SilkS"))
    (fp_line (start 0.5 0.9) (end -0.5 0.9)
      (stroke (width 0.15) (type solid)) (layer "F.SilkS"))
    (fp_line (start 0.5 0.9) (end 0.5 0.7)
      (stroke (width 0.15) (type solid)) (layer "F.SilkS"))
    (fp_line (start 0.508 -0.9) (end -0.5 -0.9)
      (stroke (width 0.15) (type solid)) (layer "F.SilkS"))
    (fp_line (start 0.508 -0.9) (end 0.508 -0.592)
      (stroke (width 0.15) (type solid)) (layer "F.SilkS"))
    (fp_rect (start -1 -1.05) (end 1 1.05)
      (stroke (width 0.05) (type solid)) (fill none) (layer "F.CrtYd"))
    (fp_line (start -0.05 -0.9) (end -0.45 -0.5)
      (stroke (width 0.15) (type solid)) (layer "F.Fab"))
    (fp_rect (start 0.45 0.9) (end -0.45 -0.9)
      (stroke (width 0.15) (type solid)) (fill none) (layer "F.Fab"))
    (pad "1" smd rect (at -0.652 -0.5 90) (size 0.6 0.5) (layers "F.Cu" "F.Paste" "F.Mask")
      (net 161 "/Reset logic/PS_RST") (pinfunction "B") (pintype "input"))
    (pad "2" smd rect (at -0.652 0.498 90) (size 0.6 0.5) (layers "F.Cu" "F.Paste" "F.Mask")
      (net 1 "GND") (pinfunction "E") (pintype "passive"))
    (pad "3" smd rect (at 0.65 0 90) (size 0.6 0.5) (layers "F.Cu" "F.Paste" "F.Mask")
      (net 151 "/Debug and JTAG/~{PS_POR}") (pinfunction "C") (pintype "passive"))
  )
	(footprint "kria-k26-devboard-footprints:SOT-416" (layer "F.Cu")
    (at 111.000001 136.2 90)
    (descr "SOT-416")
    (tags "SOT-416")
    (property "Author" "Antmicro")
    (property "License" "Apache-2.0")
    (property "MPN" "DTC014TEBTL")
    (property "Manufacturer" "ROHM Semiconductor")
    (property "Sheetfile" "reset.kicad_sch")
    (property "Sheetname" "Reset logic")
    (property "ki_description" "Digital NPN Transistor, 10k/NONE, EMT-3")
    (attr smd)
    (fp_text reference "Q9" (at 1.11 -0.800001 180) (layer "F.SilkS")
        (effects (font (size 0.7 0.7) (thickness 0.15)) (justify left bottom))
    )
    (fp_text value "DTC014T_SOT-416" (at 0 2 90) (layer "F.Fab") hide
        (effects (font (size 0.7 0.7) (thickness 0.15)) (justify left bottom))
    )
    (fp_text user "License: Apache-2.0" (at -1 5.802 90) (layer "F.Fab") hide
        (effects (font (size 0.7 0.7) (thickness 0.15)) (justify left bottom))
    )
    (fp_text user "${REFERENCE}" (at -1 3.4 90) (layer "F.Fab") hide
        (effects (font (size 0.7 0.7) (thickness 0.15)) (justify left bottom))
    )
    (fp_text user "Author: Antmicro" (at -1 4.602 90) (layer "F.Fab") hide
        (effects (font (size 0.7 0.7) (thickness 0.15)) (justify left bottom))
    )
    (fp_line (start -0.5 -0.15) (end -0.5 0.15)
      (stroke (width 0.15) (type solid)) (layer "F.SilkS"))
    (fp_line (start 0.5 0.9) (end -0.5 0.9)
      (stroke (width 0.15) (type solid)) (layer "F.SilkS"))
    (fp_line (start 0.5 0.9) (end 0.5 0.7)
      (stroke (width 0.15) (type solid)) (layer "F.SilkS"))
    (fp_line (start 0.508 -0.9) (end -0.5 -0.9)
      (stroke (width 0.15) (type solid)) (layer "F.SilkS"))
    (fp_line (start 0.508 -0.9) (end 0.508 -0.592)
      (stroke (width 0.15) (type solid)) (layer "F.SilkS"))
    (fp_rect (start -1 -1.05) (end 1 1.05)
      (stroke (width 0.05) (type solid)) (fill none) (layer "F.CrtYd"))
    (fp_line (start -0.05 -0.9) (end -0.45 -0.5)
      (stroke (width 0.15) (type solid)) (layer "F.Fab"))
    (fp_rect (start 0.45 0.9) (end -0.45 -0.9)
      (stroke (width 0.15) (type solid)) (fill none) (layer "F.Fab"))
    (pad "1" smd rect (at -0.652 -0.5 90) (size 0.6 0.5) (layers "F.Cu" "F.Paste" "F.Mask")
      (net 161 "/Reset logic/PS_RST") (pinfunction "B") (pintype "input"))
    (pad "2" smd rect (at -0.652 0.498 90) (size 0.6 0.5) (layers "F.Cu" "F.Paste" "F.Mask")
      (net 1 "GND") (pinfunction "E") (pintype "passive"))
    (pad "3" smd rect (at 0.65 0 90) (size 0.6 0.5) (layers "F.Cu" "F.Paste" "F.Mask")
      (net 185 "/Clock distribution/PS_CLK_EN") (pinfunction "C") (pintype "passive"))
  )
	(footprint "kria-k26-devboard-footprints:SOT-416" (layer "F.Cu")
    (at 118.65 120.45 180)
    (descr "SOT-416")
    (tags "SOT-416")
    (property "Author" "Antmicro")
    (property "License" "Apache-2.0")
    (property "MPN" "DTC014TEBTL")
    (property "Manufacturer" "ROHM Semiconductor")
    (property "Sheetfile" "clock.kicad_sch")
    (property "Sheetname" "Clock distribution")
    (property "ki_description" "Digital NPN Transistor, 10k/NONE, EMT-3")
    (attr smd)
    (fp_text reference "Q3" (at -1.19 -0.39 180) (layer "F.SilkS")
        (effects (font (size 0.7 0.7) (thickness 0.15)) (justify left bottom))
    )
    (fp_text value "DTC014T_SOT-416" (at 0 2 180) (layer "F.Fab") hide
        (effects (font (size 0.7 0.7) (thickness 0.15)) (justify left bottom))
    )
    (fp_text user "Author: Antmicro" (at -1 4.602 180) (layer "F.Fab") hide
        (effects (font (size 0.7 0.7) (thickness 0.15)) (justify left bottom))
    )
    (fp_text user "${REFERENCE}" (at -1 3.4 180) (layer "F.Fab") hide
        (effects (font (size 0.7 0.7) (thickness 0.15)) (justify left bottom))
    )
    (fp_text user "License: Apache-2.0" (at -1 5.802 180) (layer "F.Fab") hide
        (effects (font (size 0.7 0.7) (thickness 0.15)) (justify left bottom))
    )
    (fp_line (start -0.5 -0.15) (end -0.5 0.15)
      (stroke (width 0.15) (type solid)) (layer "F.SilkS"))
    (fp_line (start 0.5 0.9) (end -0.5 0.9)
      (stroke (width 0.15) (type solid)) (layer "F.SilkS"))
    (fp_line (start 0.5 0.9) (end 0.5 0.7)
      (stroke (width 0.15) (type solid)) (layer "F.SilkS"))
    (fp_line (start 0.508 -0.9) (end -0.5 -0.9)
      (stroke (width 0.15) (type solid)) (layer "F.SilkS"))
    (fp_line (start 0.508 -0.9) (end 0.508 -0.592)
      (stroke (width 0.15) (type solid)) (layer "F.SilkS"))
    (fp_rect (start -1 -1.05) (end 1 1.05)
      (stroke (width 0.05) (type solid)) (fill none) (layer "F.CrtYd"))
    (fp_line (start -0.05 -0.9) (end -0.45 -0.5)
      (stroke (width 0.15) (type solid)) (layer "F.Fab"))
    (fp_rect (start 0.45 0.9) (end -0.45 -0.9)
      (stroke (width 0.15) (type solid)) (fill none) (layer "F.Fab"))
    (pad "1" smd rect (at -0.652 -0.5 180) (size 0.6 0.5) (layers "F.Cu" "F.Paste" "F.Mask")
      (net 185 "/Clock distribution/PS_CLK_EN") (pinfunction "B") (pintype "input"))
    (pad "2" smd rect (at -0.652 0.498 180) (size 0.6 0.5) (layers "F.Cu" "F.Paste" "F.Mask")
      (net 1 "GND") (pinfunction "E") (pintype "passive"))
    (pad "3" smd rect (at 0.65 0 180) (size 0.6 0.5) (layers "F.Cu" "F.Paste" "F.Mask")
      (net 429 "Net-(Q3-C)") (pinfunction "C") (pintype "passive"))
  )
	(footprint "kria-k26-devboard-footprints:R_0402_1005Metric" (layer "F.Cu")
    (at 143.153411 111.695908 -90)
    (descr "Resistor SMD 0402")
    (tags "resistor SMD 0402")
    (property "Author" "Antmicro")
    (property "License" "Apache-2.0")
    (property "MPN" "CR0402-FX-2201GLF")
    (property "Manufacturer" "Bourns")
    (property "Sheetfile" "debug.kicad_sch")
    (property "Sheetname" "Debug and JTAG")
    (property "Tolerance" "1%")
    (property "Val" "2k2")
    (property "ki_description" "2k2 resistor in 0402 package with 1% tolerance")
    (attr smd)
    (fp_text reference "R107" (at -0.525908 5.803411) (layer "F.SilkS")
        (effects (font (size 0.7 0.7) (thickness 0.15)) (justify left bottom))
    )
    (fp_text value "R_2k2_0402" (at 0 1.4 -90) (layer "F.Fab") hide
        (effects (font (size 0.7 0.7) (thickness 0.15)) (justify left bottom))
    )
    (fp_text user "${REFERENCE}" (at -0.95 3.168 -90) (layer "F.Fab") hide
        (effects (font (size 0.7 0.7) (thickness 0.15)) (justify left bottom))
    )
    (fp_text user "License: Apache-2.0" (at -0.95 5.169 -90) (layer "F.Fab") hide
        (effects (font (size 0.7 0.7) (thickness 0.15)) (justify left bottom))
    )
    (fp_text user "Author: Antmicro" (at -0.95 4.169 -90) (layer "F.Fab") hide
        (effects (font (size 0.7 0.7) (thickness 0.15)) (justify left bottom))
    )
    (fp_rect (start -0.93 -0.47) (end 0.93 0.47)
      (stroke (width 0.05) (type solid)) (fill none) (layer "F.CrtYd"))
    (fp_rect (start -0.5 -0.25) (end 0.5 0.25)
      (stroke (width 0.15) (type solid)) (fill none) (layer "F.Fab"))
    (pad "1" smd roundrect (at -0.485 0 270) (size 0.59 0.64) (layers "F.Cu" "F.Paste" "F.Mask") (roundrect_rratio 0.25)
      (net 682 "Net-(U39-DO)") (pintype "passive"))
    (pad "2" smd roundrect (at 0.485 0 270) (size 0.59 0.64) (layers "F.Cu" "F.Paste" "F.Mask") (roundrect_rratio 0.25)
      (net 230 "/Debug and JTAG/EEDATA") (pintype "passive"))
  )
	(footprint "kria-k26-devboard-footprints:R_0402_1005Metric" (layer "F.Cu")
    (at 141.15 110.31)
    (descr "Resistor SMD 0402")
    (tags "resistor SMD 0402")
    (property "Author" "Antmicro")
    (property "License" "Apache-2.0")
    (property "MPN" "CR0402-FX-1002GLF")
    (property "Manufacturer" "Bourns")
    (property "Sheetfile" "debug.kicad_sch")
    (property "Sheetname" "Debug and JTAG")
    (property "Tolerance" "1%")
    (property "Val" "10k")
    (property "ki_description" "10k resistor in 0402 package with 1% tolerance")
    (attr smd)
    (fp_text reference "R106" (at -1.87 -0.58) (layer "F.SilkS")
        (effects (font (size 0.7 0.7) (thickness 0.15)) (justify left bottom))
    )
    (fp_text value "R_10k_0402" (at 0 1.4) (layer "F.Fab") hide
        (effects (font (size 0.7 0.7) (thickness 0.15)) (justify left bottom))
    )
    (fp_text user "Author: Antmicro" (at -0.95 4.169) (layer "F.Fab") hide
        (effects (font (size 0.7 0.7) (thickness 0.15)) (justify left bottom))
    )
    (fp_text user "${REFERENCE}" (at -0.95 3.168) (layer "F.Fab") hide
        (effects (font (size 0.7 0.7) (thickness 0.15)) (justify left bottom))
    )
    (fp_text user "License: Apache-2.0" (at -0.95 5.169) (layer "F.Fab") hide
        (effects (font (size 0.7 0.7) (thickness 0.15)) (justify left bottom))
    )
    (fp_rect (start -0.93 -0.47) (end 0.93 0.47)
      (stroke (width 0.05) (type solid)) (fill none) (layer "F.CrtYd"))
    (fp_rect (start -0.5 -0.25) (end 0.5 0.25)
      (stroke (width 0.15) (type solid)) (fill none) (layer "F.Fab"))
    (pad "1" smd roundrect (at -0.485 0) (size 0.59 0.64) (layers "F.Cu" "F.Paste" "F.Mask") (roundrect_rratio 0.25)
      (net 138 "/Debug and JTAG/USB_3V3") (pintype "passive"))
    (pad "2" smd roundrect (at 0.485 0) (size 0.59 0.64) (layers "F.Cu" "F.Paste" "F.Mask") (roundrect_rratio 0.25)
      (net 682 "Net-(U39-DO)") (pintype "passive"))
  )
	(footprint "kria-k26-devboard-footprints:R_0402_1005Metric" (layer "F.Cu")
    (at 143.0827 113.605097 90)
    (descr "Resistor SMD 0402")
    (tags "resistor SMD 0402")
    (property "Author" "Antmicro")
    (property "License" "Apache-2.0")
    (property "MPN" "CR0402-FX-1002GLF")
    (property "Manufacturer" "Bourns")
    (property "Sheetfile" "debug.kicad_sch")
    (property "Sheetname" "Debug and JTAG")
    (property "Tolerance" "1%")
    (property "Val" "10k")
    (property "ki_description" "10k resistor in 0402 package with 1% tolerance")
    (attr smd)
    (fp_text reference "R108" (at -0.844903 -7.5827) (layer "F.SilkS")
        (effects (font (size 0.7 0.7) (thickness 0.15)) (justify left bottom))
    )
    (fp_text value "R_10k_0402" (at 0 1.4 90) (layer "F.Fab") hide
        (effects (font (size 0.7 0.7) (thickness 0.15)) (justify left bottom))
    )
    (fp_text user "Author: Antmicro" (at -0.95 4.169 90) (layer "F.Fab") hide
        (effects (font (size 0.7 0.7) (thickness 0.15)) (justify left bottom))
    )
    (fp_text user "${REFERENCE}" (at -0.95 3.168 90) (layer "F.Fab") hide
        (effects (font (size 0.7 0.7) (thickness 0.15)) (justify left bottom))
    )
    (fp_text user "License: Apache-2.0" (at -0.95 5.169 90) (layer "F.Fab") hide
        (effects (font (size 0.7 0.7) (thickness 0.15)) (justify left bottom))
    )
    (fp_rect (start -0.93 -0.47) (end 0.93 0.47)
      (stroke (width 0.05) (type solid)) (fill none) (layer "F.CrtYd"))
    (fp_rect (start -0.5 -0.25) (end 0.5 0.25)
      (stroke (width 0.15) (type solid)) (fill none) (layer "F.Fab"))
    (pad "1" smd roundrect (at -0.485 0 90) (size 0.59 0.64) (layers "F.Cu" "F.Paste" "F.Mask") (roundrect_rratio 0.25)
      (net 138 "/Debug and JTAG/USB_3V3") (pintype "passive"))
    (pad "2" smd roundrect (at 0.485 0 90) (size 0.59 0.64) (layers "F.Cu" "F.Paste" "F.Mask") (roundrect_rratio 0.25)
      (net 231 "/Debug and JTAG/EECLK") (pintype "passive"))
  )
	(footprint "kria-k26-devboard-footprints:R_0402_1005Metric" (layer "F.Cu")
    (at 141.46 115.07)
    (descr "Resistor SMD 0402")
    (tags "resistor SMD 0402")
    (property "Author" "Antmicro")
    (property "License" "Apache-2.0")
    (property "MPN" "CR0402-FX-1002GLF")
    (property "Manufacturer" "Bourns")
    (property "Sheetfile" "debug.kicad_sch")
    (property "Sheetname" "Debug and JTAG")
    (property "Tolerance" "1%")
    (property "Val" "10k")
    (property "ki_description" "10k resistor in 0402 package with 1% tolerance")
    (attr smd)
    (fp_text reference "R110" (at -3.68 0.33) (layer "F.SilkS")
        (effects (font (size 0.7 0.7) (thickness 0.15)) (justify left bottom))
    )
    (fp_text value "R_10k_0402" (at 0 1.4) (layer "F.Fab") hide
        (effects (font (size 0.7 0.7) (thickness 0.15)) (justify left bottom))
    )
    (fp_text user "Author: Antmicro" (at -0.95 4.169) (layer "F.Fab") hide
        (effects (font (size 0.7 0.7) (thickness 0.15)) (justify left bottom))
    )
    (fp_text user "License: Apache-2.0" (at -0.95 5.169) (layer "F.Fab") hide
        (effects (font (size 0.7 0.7) (thickness 0.15)) (justify left bottom))
    )
    (fp_text user "${REFERENCE}" (at -0.95 3.168) (layer "F.Fab") hide
        (effects (font (size 0.7 0.7) (thickness 0.15)) (justify left bottom))
    )
    (fp_rect (start -0.93 -0.47) (end 0.93 0.47)
      (stroke (width 0.05) (type solid)) (fill none) (layer "F.CrtYd"))
    (fp_rect (start -0.5 -0.25) (end 0.5 0.25)
      (stroke (width 0.15) (type solid)) (fill none) (layer "F.Fab"))
    (pad "1" smd roundrect (at -0.485 0) (size 0.59 0.64) (layers "F.Cu" "F.Paste" "F.Mask") (roundrect_rratio 0.25)
      (net 138 "/Debug and JTAG/USB_3V3") (pintype "passive"))
    (pad "2" smd roundrect (at 0.485 0) (size 0.59 0.64) (layers "F.Cu" "F.Paste" "F.Mask") (roundrect_rratio 0.25)
      (net 232 "/Debug and JTAG/EECS") (pintype "passive"))
  )
)
